(kicad_pcb
	(version 20260206)
	(generator "pcbnew")
	(generator_version "10.0")
	(general
		(thickness 1.6)
		(legacy_teardrops no)
	)
	(paper "A4")
	(title_block
		(title "12092022_DA0F0TMDCD0_F0T_Management_Board_D_brd_V3_OCP.brd")
		(comment 1 "Grand Teton / footprints 534-539 of 1440")
	)
	(layers
		(0 "F.Cu" signal "TOP")
		(4 "In1.Cu" signal "GND")
		(6 "In2.Cu" signal "IN1")
		(8 "In3.Cu" signal "GND1")
		(10 "In4.Cu" signal "IN2")
		(12 "In5.Cu" signal "VCC")
		(14 "In6.Cu" signal "VCC1")
		(16 "In7.Cu" signal "IN3")
		(18 "In8.Cu" signal "GND2")
		(20 "In9.Cu" signal "IN4")
		(22 "In10.Cu" signal "GND3")
		(2 "B.Cu" signal "BOTTOM")
		(9 "F.Adhes" user "F.Adhesive")
		(11 "B.Adhes" user "B.Adhesive")
		(13 "F.Paste" user "Package Geometry/Pastemask Top")
		(15 "B.Paste" user "Package Geometry/Pastemask Bottom")
		(5 "F.SilkS" user "Ref Des/Silkscreen Top")
		(7 "B.SilkS" user "Ref Des/Silkscreen Bottom")
		(1 "F.Mask" user "Board Geometry/Soldermask Top")
		(3 "B.Mask" user "Board Geometry/Soldermask Bottom")
		(17 "Dwgs.User" user "User.Drawings")
		(19 "Cmts.User" user "User.Comments")
		(21 "Eco1.User" user "User.Eco1")
		(23 "Eco2.User" user "User.Eco2")
		(25 "Edge.Cuts" user "Board Geometry/Outline")
		(27 "Margin" user)
		(31 "F.CrtYd" user "Package Geometry/Place Bound Top")
		(29 "B.CrtYd" user "Package Geometry/Place Bound Bottom")
		(35 "F.Fab" user "Ref Des/Assembly Top")
		(33 "B.Fab" user "Ref Des/Assembly Bottom")
	)
	(footprint ""
		(layer "F.Cu")
		(at 68.4276 -71.882 -90)
		(property "Reference" "R238"
			(at 0 0 270)
			(layer "F.SilkS")
			(hide yes)
			(effects
				(font
					(size 1.27 1.27)
				)
			)
		)
		(property "Value" ""
			(at 0 0 270)
			(layer "F.Fab")
			(effects
				(font
					(size 1.27 1.27)
				)
			)
		)
		(duplicate_pad_numbers_are_jumpers no)
		(fp_line
			(start -0.7874 0.4064)
			(end -0.7874 -0.4064)
			(stroke
				(width 0.1524)
				(type default)
			)
			(layer "F.SilkS")
		)
		(fp_line
			(start 0.7874 0.4064)
			(end -0.7874 0.4064)
			(stroke
				(width 0.1524)
				(type default)
			)
			(layer "F.SilkS")
		)
		(fp_line
			(start -0.7874 -0.4064)
			(end 0.7874 -0.4064)
			(stroke
				(width 0.1524)
				(type default)
			)
			(layer "F.SilkS")
		)
		(fp_line
			(start 0.7874 -0.4064)
			(end 0.7874 0.4064)
			(stroke
				(width 0.1524)
				(type default)
			)
			(layer "F.SilkS")
		)
		(fp_line
			(start -0.67945 0.3048)
			(end -0.67945 -0.305054)
			(stroke
				(width 0.1)
				(type default)
			)
			(layer "F.Fab")
		)
		(fp_line
			(start -0.12065 0.3048)
			(end -0.67945 0.3048)
			(stroke
				(width 0.1)
				(type default)
			)
			(layer "F.Fab")
		)
		(fp_line
			(start 0.120396 0.3048)
			(end 0.120396 0.2794)
			(stroke
				(width 0.1)
				(type default)
			)
			(layer "F.Fab")
		)
		(fp_line
			(start 0.67945 0.3048)
			(end 0.120396 0.3048)
			(stroke
				(width 0.1)
				(type default)
			)
			(layer "F.Fab")
		)
		(fp_line
			(start -0.12065 0.2794)
			(end -0.12065 0.3048)
			(stroke
				(width 0.1)
				(type default)
			)
			(layer "F.Fab")
		)
		(fp_line
			(start 0.120396 0.2794)
			(end -0.12065 0.2794)
			(stroke
				(width 0.1)
				(type default)
			)
			(layer "F.Fab")
		)
		(fp_line
			(start -0.12065 -0.2794)
			(end 0.12065 -0.2794)
			(stroke
				(width 0.1)
				(type default)
			)
			(layer "F.Fab")
		)
		(fp_line
			(start 0.12065 -0.2794)
			(end 0.12065 -0.3048)
			(stroke
				(width 0.1)
				(type default)
			)
			(layer "F.Fab")
		)
		(fp_line
			(start 0.12065 -0.3048)
			(end 0.67945 -0.3048)
			(stroke
				(width 0.1)
				(type default)
			)
			(layer "F.Fab")
		)
		(fp_line
			(start 0.67945 -0.3048)
			(end 0.67945 0.3048)
			(stroke
				(width 0.1)
				(type default)
			)
			(layer "F.Fab")
		)
		(fp_line
			(start -0.67945 -0.305054)
			(end -0.12065 -0.305054)
			(stroke
				(width 0.1)
				(type default)
			)
			(layer "F.Fab")
		)
		(fp_line
			(start -0.12065 -0.305054)
			(end -0.12065 -0.2794)
			(stroke
				(width 0.1)
				(type default)
			)
			(layer "F.Fab")
		)
		(pad "1" smd circle
			(at -0.40005 0 270)
			(size 0 0)
			(layers "F.Cu" "F.Mask" "F.Paste")
			(net "P3V3_AUX")
		)
		(pad "2" smd circle
			(at 0.40005 0 270)
			(size 0 0)
			(layers "F.Cu" "F.Mask" "F.Paste")
			(net "SPI_BMC_TPM_CS2_R_N")
		)
	)
	(footprint ""
		(layer "F.Cu")
		(at 12.319 -97.536 180)
		(property "Reference" "R841"
			(at 0 0 180)
			(layer "F.SilkS")
			(hide yes)
			(effects
				(font
					(size 1.27 1.27)
				)
			)
		)
		(property "Value" ""
			(at 0 0 180)
			(layer "F.Fab")
			(effects
				(font
					(size 1.27 1.27)
				)
			)
		)
		(duplicate_pad_numbers_are_jumpers no)
		(fp_line
			(start 0.7874 0.4064)
			(end -0.7874 0.4064)
			(stroke
				(width 0.1524)
				(type default)
			)
			(layer "F.SilkS")
		)
		(fp_line
			(start 0.7874 -0.4064)
			(end 0.7874 0.4064)
			(stroke
				(width 0.1524)
				(type default)
			)
			(layer "F.SilkS")
		)
		(fp_line
			(start -0.7874 0.4064)
			(end -0.7874 -0.4064)
			(stroke
				(width 0.1524)
				(type default)
			)
			(layer "F.SilkS")
		)
		(fp_line
			(start -0.7874 -0.4064)
			(end 0.7874 -0.4064)
			(stroke
				(width 0.1524)
				(type default)
			)
			(layer "F.SilkS")
		)
		(fp_line
			(start 0.67945 0.3048)
			(end 0.120396 0.3048)
			(stroke
				(width 0.1)
				(type default)
			)
			(layer "F.Fab")
		)
		(fp_line
			(start 0.67945 -0.3048)
			(end 0.67945 0.3048)
			(stroke
				(width 0.1)
				(type default)
			)
			(layer "F.Fab")
		)
		(fp_line
			(start 0.12065 -0.2794)
			(end 0.12065 -0.3048)
			(stroke
				(width 0.1)
				(type default)
			)
			(layer "F.Fab")
		)
		(fp_line
			(start 0.12065 -0.3048)
			(end 0.67945 -0.3048)
			(stroke
				(width 0.1)
				(type default)
			)
			(layer "F.Fab")
		)
		(fp_line
			(start 0.120396 0.3048)
			(end 0.120396 0.2794)
			(stroke
				(width 0.1)
				(type default)
			)
			(layer "F.Fab")
		)
		(fp_line
			(start 0.120396 0.2794)
			(end -0.12065 0.2794)
			(stroke
				(width 0.1)
				(type default)
			)
			(layer "F.Fab")
		)
		(fp_line
			(start -0.12065 0.3048)
			(end -0.67945 0.3048)
			(stroke
				(width 0.1)
				(type default)
			)
			(layer "F.Fab")
		)
		(fp_line
			(start -0.12065 0.2794)
			(end -0.12065 0.3048)
			(stroke
				(width 0.1)
				(type default)
			)
			(layer "F.Fab")
		)
		(fp_line
			(start -0.12065 -0.2794)
			(end 0.12065 -0.2794)
			(stroke
				(width 0.1)
				(type default)
			)
			(layer "F.Fab")
		)
		(fp_line
			(start -0.12065 -0.305054)
			(end -0.12065 -0.2794)
			(stroke
				(width 0.1)
				(type default)
			)
			(layer "F.Fab")
		)
		(fp_line
			(start -0.67945 0.3048)
			(end -0.67945 -0.305054)
			(stroke
				(width 0.1)
				(type default)
			)
			(layer "F.Fab")
		)
		(fp_line
			(start -0.67945 -0.305054)
			(end -0.12065 -0.305054)
			(stroke
				(width 0.1)
				(type default)
			)
			(layer "F.Fab")
		)
		(pad "1" smd circle
			(at -0.40005 0 180)
			(size 0 0)
			(layers "F.Cu" "F.Mask" "F.Paste")
			(net "PWRGD_SYS_PWROK_PLD")
		)
		(pad "2" smd circle
			(at 0.40005 0 180)
			(size 0 0)
			(layers "F.Cu" "F.Mask" "F.Paste")
			(net "PWRGD_SYS_PWROK")
		)
	)
	(footprint ""
		(layer "F.Cu")
		(at 16.235172 -31.66237 90)
		(property "Reference" "R399"
			(at 0 0 90)
			(layer "F.SilkS")
			(hide yes)
			(effects
				(font
					(size 1.27 1.27)
				)
			)
		)
		(property "Value" ""
			(at 0 0 90)
			(layer "F.Fab")
			(effects
				(font
					(size 1.27 1.27)
				)
			)
		)
		(duplicate_pad_numbers_are_jumpers no)
		(fp_line
			(start 0.7874 -0.4064)
			(end 0.7874 0.4064)
			(stroke
				(width 0.1524)
				(type default)
			)
			(layer "F.SilkS")
		)
		(fp_line
			(start -0.7874 -0.4064)
			(end 0.7874 -0.4064)
			(stroke
				(width 0.1524)
				(type default)
			)
			(layer "F.SilkS")
		)
		(fp_line
			(start 0.7874 0.4064)
			(end -0.7874 0.4064)
			(stroke
				(width 0.1524)
				(type default)
			)
			(layer "F.SilkS")
		)
		(fp_line
			(start -0.7874 0.4064)
			(end -0.7874 -0.4064)
			(stroke
				(width 0.1524)
				(type default)
			)
			(layer "F.SilkS")
		)
		(fp_line
			(start -0.12065 -0.305054)
			(end -0.12065 -0.2794)
			(stroke
				(width 0.1)
				(type default)
			)
			(layer "F.Fab")
		)
		(fp_line
			(start -0.67945 -0.305054)
			(end -0.12065 -0.305054)
			(stroke
				(width 0.1)
				(type default)
			)
			(layer "F.Fab")
		)
		(fp_line
			(start 0.67945 -0.3048)
			(end 0.67945 0.3048)
			(stroke
				(width 0.1)
				(type default)
			)
			(layer "F.Fab")
		)
		(fp_line
			(start 0.12065 -0.3048)
			(end 0.67945 -0.3048)
			(stroke
				(width 0.1)
				(type default)
			)
			(layer "F.Fab")
		)
		(fp_line
			(start 0.12065 -0.2794)
			(end 0.12065 -0.3048)
			(stroke
				(width 0.1)
				(type default)
			)
			(layer "F.Fab")
		)
		(fp_line
			(start -0.12065 -0.2794)
			(end 0.12065 -0.2794)
			(stroke
				(width 0.1)
				(type default)
			)
			(layer "F.Fab")
		)
		(fp_line
			(start 0.120396 0.2794)
			(end -0.12065 0.2794)
			(stroke
				(width 0.1)
				(type default)
			)
			(layer "F.Fab")
		)
		(fp_line
			(start -0.12065 0.2794)
			(end -0.12065 0.3048)
			(stroke
				(width 0.1)
				(type default)
			)
			(layer "F.Fab")
		)
		(fp_line
			(start 0.67945 0.3048)
			(end 0.120396 0.3048)
			(stroke
				(width 0.1)
				(type default)
			)
			(layer "F.Fab")
		)
		(fp_line
			(start 0.120396 0.3048)
			(end 0.120396 0.2794)
			(stroke
				(width 0.1)
				(type default)
			)
			(layer "F.Fab")
		)
		(fp_line
			(start -0.12065 0.3048)
			(end -0.67945 0.3048)
			(stroke
				(width 0.1)
				(type default)
			)
			(layer "F.Fab")
		)
		(fp_line
			(start -0.67945 0.3048)
			(end -0.67945 -0.305054)
			(stroke
				(width 0.1)
				(type default)
			)
			(layer "F.Fab")
		)
		(pad "1" smd circle
			(at -0.40005 0 90)
			(size 0 0)
			(layers "F.Cu" "F.Mask" "F.Paste")
			(net "EN_P1V0_AUX")
		)
		(pad "2" smd circle
			(at 0.40005 0 90)
			(size 0 0)
			(layers "F.Cu" "F.Mask" "F.Paste")
			(net "EN_P1V0_AUX_R")
		)
	)
	(footprint ""
		(layer "F.Cu")
		(at 82.804 -80.518 -90)
		(property "Reference" "PL29"
			(at 0 0 270)
			(layer "F.SilkS")
			(hide yes)
			(effects
				(font
					(size 1.27 1.27)
				)
			)
		)
		(property "Value" ""
			(at 0 0 270)
			(layer "F.Fab")
			(effects
				(font
					(size 1.27 1.27)
				)
			)
		)
		(duplicate_pad_numbers_are_jumpers no)
		(fp_line
			(start -1.27 0.5842)
			(end -1.27 -0.5842)
			(stroke
				(width 0.1524)
				(type default)
			)
			(layer "F.SilkS")
		)
		(fp_line
			(start -0.127 0.5842)
			(end -0.127 -0.5842)
			(stroke
				(width 0.1524)
				(type default)
			)
			(layer "F.SilkS")
		)
		(fp_line
			(start 0.127 0.5842)
			(end 0.127 -0.5842)
			(stroke
				(width 0.1524)
				(type default)
			)
			(layer "F.SilkS")
		)
		(fp_line
			(start 1.27 0.5842)
			(end -1.27 0.5842)
			(stroke
				(width 0.1524)
				(type default)
			)
			(layer "F.SilkS")
		)
		(fp_line
			(start 1.27 0.5842)
			(end 1.27 -0.5842)
			(stroke
				(width 0.1524)
				(type default)
			)
			(layer "F.SilkS")
		)
		(fp_line
			(start -1.27 -0.5588)
			(end -1.27 -0.5842)
			(stroke
				(width 0.1524)
				(type default)
			)
			(layer "F.SilkS")
		)
		(fp_line
			(start -1.27 -0.5842)
			(end 1.27 -0.5842)
			(stroke
				(width 0.1524)
				(type default)
			)
			(layer "F.SilkS")
		)
		(fp_line
			(start -0.9144 0.508)
			(end -0.9144 0.406654)
			(stroke
				(width 0.1)
				(type default)
			)
			(layer "F.Fab")
		)
		(fp_line
			(start 0.9144 0.508)
			(end -0.9144 0.508)
			(stroke
				(width 0.1)
				(type default)
			)
			(layer "F.Fab")
		)
		(fp_line
			(start -1.194308 0.406654)
			(end -1.194308 -0.406654)
			(stroke
				(width 0.1)
				(type default)
			)
			(layer "F.Fab")
		)
		(fp_line
			(start -0.9144 0.406654)
			(end -1.194308 0.406654)
			(stroke
				(width 0.1)
				(type default)
			)
			(layer "F.Fab")
		)
		(fp_line
			(start 0.9144 0.4064)
			(end 0.9144 0.508)
			(stroke
				(width 0.1)
				(type default)
			)
			(layer "F.Fab")
		)
		(fp_line
			(start 1.1938 0.4064)
			(end 0.9144 0.4064)
			(stroke
				(width 0.1)
				(type default)
			)
			(layer "F.Fab")
		)
		(fp_line
			(start -1.194308 -0.406654)
			(end -0.9144 -0.406654)
			(stroke
				(width 0.1)
				(type default)
			)
			(layer "F.Fab")
		)
		(fp_line
			(start -0.9144 -0.406654)
			(end -0.9144 -0.508)
			(stroke
				(width 0.1)
				(type default)
			)
			(layer "F.Fab")
		)
		(fp_line
			(start 0.9144 -0.406654)
			(end 1.1938 -0.406654)
			(stroke
				(width 0.1)
				(type default)
			)
			(layer "F.Fab")
		)
		(fp_line
			(start 1.1938 -0.406654)
			(end 1.1938 0.4064)
			(stroke
				(width 0.1)
				(type default)
			)
			(layer "F.Fab")
		)
		(fp_line
			(start -0.9144 -0.508)
			(end 0.9144 -0.508)
			(stroke
				(width 0.1)
				(type default)
			)
			(layer "F.Fab")
		)
		(fp_line
			(start 0.9144 -0.508)
			(end 0.9144 -0.406654)
			(stroke
				(width 0.1)
				(type default)
			)
			(layer "F.Fab")
		)
		(pad "1" smd rect
			(at -0.7366 0 180)
			(size 0.7112 0.8128)
			(layers "F.Cu" "F.Mask" "F.Paste")
			(net "P12V_AUX")
		)
		(pad "2" smd rect
			(at 0.7366 0 180)
			(size 0.7112 0.8128)
			(layers "F.Cu" "F.Mask" "F.Paste")
			(net "SW_P1V2_AUX_FLT")
		)
	)
	(footprint ""
		(layer "F.Cu")
		(at 22.979888 -6.290056)
		(property "Reference" "D15"
			(at -1.135888 -2.547874 0)
			(unlocked yes)
			(layer "F.SilkS")
			(effects
				(font
					(size 0.7874 0.5842)
					(thickness 0.1524)
				)
				(justify left)
			)
		)
		(property "Value" ""
			(at 0 0 0)
			(layer "F.Fab")
			(effects
				(font
					(size 1.27 1.27)
				)
			)
		)
		(duplicate_pad_numbers_are_jumpers no)
		(fp_line
			(start -1.080008 -1.999996)
			(end 3.620008 -1.999996)
			(stroke
				(width 0.1524)
				(type default)
			)
			(layer "F.SilkS")
		)
		(fp_line
			(start -1.080008 3.999992)
			(end -1.080008 -1.999996)
			(stroke
				(width 0.1524)
				(type default)
			)
			(layer "F.SilkS")
		)
		(fp_line
			(start -0.230124 3.999992)
			(end -1.080008 3.999992)
			(stroke
				(width 0.1524)
				(type default)
			)
			(layer "F.SilkS")
		)
		(fp_line
			(start -0.230124 5.199888)
			(end -0.230124 3.999992)
			(stroke
				(width 0.1524)
				(type default)
			)
			(layer "F.SilkS")
		)
		(fp_line
			(start 2.770124 3.999992)
			(end 2.770124 5.199888)
			(stroke
				(width 0.1524)
				(type default)
			)
			(layer "F.SilkS")
		)
		(fp_line
			(start 3.620008 -1.999996)
			(end 3.620008 3.999992)
			(stroke
				(width 0.1524)
				(type default)
			)
			(layer "F.SilkS")
		)
		(fp_line
			(start 3.620008 3.999992)
			(end 2.770124 3.999992)
			(stroke
				(width 0.1524)
				(type default)
			)
			(layer "F.SilkS")
		)
		(fp_arc
			(start 1.27 6.700012)
			(mid 0.209252 6.260636)
			(end -0.230124 5.199888)
			(stroke
				(width 0.1524)
				(type default)
			)
			(layer "F.SilkS")
		)
		(fp_arc
			(start 2.770124 5.199888)
			(mid 2.330748 6.260636)
			(end 1.27 6.700012)
			(stroke
				(width 0.1524)
				(type default)
			)
			(layer "F.SilkS")
		)
		(fp_line
			(start -1.080008 -1.999996)
			(end 3.620008 -1.999996)
			(stroke
				(width 0.1)
				(type default)
			)
			(layer "F.Fab")
		)
		(fp_line
			(start -1.080008 3.999992)
			(end -1.080008 -1.999996)
			(stroke
				(width 0.1)
				(type default)
			)
			(layer "F.Fab")
		)
		(fp_line
			(start -0.230124 3.999992)
			(end -1.080008 3.999992)
			(stroke
				(width 0.1)
				(type default)
			)
			(layer "F.Fab")
		)
		(fp_line
			(start -0.230124 5.199888)
			(end -0.230124 3.999992)
			(stroke
				(width 0.1)
				(type default)
			)
			(layer "F.Fab")
		)
		(fp_line
			(start 2.770124 3.999992)
			(end 2.770124 5.199888)
			(stroke
				(width 0.1)
				(type default)
			)
			(layer "F.Fab")
		)
		(fp_line
			(start 3.620008 -1.999996)
			(end 3.620008 3.999992)
			(stroke
				(width 0.1)
				(type default)
			)
			(layer "F.Fab")
		)
		(fp_line
			(start 3.620008 3.999992)
			(end 2.770124 3.999992)
			(stroke
				(width 0.1)
				(type default)
			)
			(layer "F.Fab")
		)
		(fp_arc
			(start 1.27 6.700012)
			(mid 0.209252 6.260636)
			(end -0.230124 5.199888)
			(stroke
				(width 0.1)
				(type default)
			)
			(layer "F.Fab")
		)
		(fp_arc
			(start 2.770124 5.199888)
			(mid 2.330748 6.260636)
			(end 1.27 6.700012)
			(stroke
				(width 0.1)
				(type default)
			)
			(layer "F.Fab")
		)
		(pad "A" thru_hole rect
			(at 0 0)
			(size 1.2192 1.2192)
			(drill 0.8128)
			(layers "*.Cu" "*.Mask")
			(remove_unused_layers no)
			(net "HDD_LED_P5V_AUX")
			(clearance 0.0508)
			(thermal_gap 0.0508)
			(padstack
				(mode front_inner_back)
				(layer "Inner"
					(shape circle)
					(size 1.2192 1.2192)
					(clearance 0.0508)
				)
				(layer "B.Cu"
					(shape rect)
					(size 1.2192 1.2192)
					(clearance 0.0508)
				)
			)
		)
		(pad "C" thru_hole circle
			(at 2.54 0)
			(size 1.2192 1.2192)
			(drill 0.8128)
			(layers "*.Cu" "*.Mask")
			(remove_unused_layers no)
			(net "HDD_LED_BUF_R")
			(clearance 0.0508)
			(thermal_gap 0.0508)
		)
	)
	(footprint ""
		(layer "F.Cu")
		(at 49.779682 -34.637726 -90)
		(property "Reference" "R590"
			(at 0 0 270)
			(layer "F.SilkS")
			(hide yes)
			(effects
				(font
					(size 1.27 1.27)
				)
			)
		)
		(property "Value" ""
			(at 0 0 270)
			(layer "F.Fab")
			(effects
				(font
					(size 1.27 1.27)
				)
			)
		)
		(duplicate_pad_numbers_are_jumpers no)
		(fp_line
			(start -0.7874 0.4064)
			(end -0.7874 -0.4064)
			(stroke
				(width 0.1524)
				(type default)
			)
			(layer "F.SilkS")
		)
		(fp_line
			(start 0.7874 0.4064)
			(end -0.7874 0.4064)
			(stroke
				(width 0.1524)
				(type default)
			)
			(layer "F.SilkS")
		)
		(fp_line
			(start -0.7874 -0.4064)
			(end 0.7874 -0.4064)
			(stroke
				(width 0.1524)
				(type default)
			)
			(layer "F.SilkS")
		)
		(fp_line
			(start 0.7874 -0.4064)
			(end 0.7874 0.4064)
			(stroke
				(width 0.1524)
				(type default)
			)
			(layer "F.SilkS")
		)
		(fp_line
			(start -0.67945 0.3048)
			(end -0.67945 -0.305054)
			(stroke
				(width 0.1)
				(type default)
			)
			(layer "F.Fab")
		)
		(fp_line
			(start -0.12065 0.3048)
			(end -0.67945 0.3048)
			(stroke
				(width 0.1)
				(type default)
			)
			(layer "F.Fab")
		)
		(fp_line
			(start 0.120396 0.3048)
			(end 0.120396 0.2794)
			(stroke
				(width 0.1)
				(type default)
			)
			(layer "F.Fab")
		)
		(fp_line
			(start 0.67945 0.3048)
			(end 0.120396 0.3048)
			(stroke
				(width 0.1)
				(type default)
			)
			(layer "F.Fab")
		)
		(fp_line
			(start -0.12065 0.2794)
			(end -0.12065 0.3048)
			(stroke
				(width 0.1)
				(type default)
			)
			(layer "F.Fab")
		)
		(fp_line
			(start 0.120396 0.2794)
			(end -0.12065 0.2794)
			(stroke
				(width 0.1)
				(type default)
			)
			(layer "F.Fab")
		)
		(fp_line
			(start -0.12065 -0.2794)
			(end 0.12065 -0.2794)
			(stroke
				(width 0.1)
				(type default)
			)
			(layer "F.Fab")
		)
		(fp_line
			(start 0.12065 -0.2794)
			(end 0.12065 -0.3048)
			(stroke
				(width 0.1)
				(type default)
			)
			(layer "F.Fab")
		)
		(fp_line
			(start 0.12065 -0.3048)
			(end 0.67945 -0.3048)
			(stroke
				(width 0.1)
				(type default)
			)
			(layer "F.Fab")
		)
		(fp_line
			(start 0.67945 -0.3048)
			(end 0.67945 0.3048)
			(stroke
				(width 0.1)
				(type default)
			)
			(layer "F.Fab")
		)
		(fp_line
			(start -0.67945 -0.305054)
			(end -0.12065 -0.305054)
			(stroke
				(width 0.1)
				(type default)
			)
			(layer "F.Fab")
		)
		(fp_line
			(start -0.12065 -0.305054)
			(end -0.12065 -0.2794)
			(stroke
				(width 0.1)
				(type default)
			)
			(layer "F.Fab")
		)
		(pad "1" smd circle
			(at -0.40005 0 270)
			(size 0 0)
			(layers "F.Cu" "F.Mask" "F.Paste")
			(net "SMB_BMC_MM3_R_SDA")
		)
		(pad "2" smd circle
			(at 0.40005 0 270)
			(size 0 0)
			(layers "F.Cu" "F.Mask" "F.Paste")
			(net "SMB_BMC_MM3_SDA")
		)
	)
)
